(kicad_pcb
	(version 20260206)
	(generator "pcbnew")
	(generator_version "10.0")
	(general
		(thickness 1.6)
		(legacy_teardrops no)
	)
	(paper "A4")
	(title_block
		(title "v1-chassis-manager — T6M_CM_d_v01_1031_1645.brd")
		(comment 1 "Open CloudServer (Microsoft) / footprints 222-228 of 2512")
	)
	(layers
		(0 "F.Cu" signal "TOP")
		(4 "In1.Cu" signal "GND1")
		(6 "In2.Cu" signal "IN1")
		(8 "In3.Cu" signal "VCC1")
		(10 "In4.Cu" signal "VCC2")
		(12 "In5.Cu" signal "GND2")
		(14 "In6.Cu" signal "IN2")
		(16 "In7.Cu" signal "IN3")
		(18 "In8.Cu" signal "GND3")
		(2 "B.Cu" signal "BOTTOM")
		(9 "F.Adhes" user "F.Adhesive")
		(11 "B.Adhes" user "B.Adhesive")
		(13 "F.Paste" user "Package Geometry/Pastemask Top")
		(15 "B.Paste" user "Package Geometry/Pastemask Bottom")
		(5 "F.SilkS" user "Ref Des/Silkscreen Top")
		(7 "B.SilkS" user "Ref Des/Silkscreen Bottom")
		(1 "F.Mask" user "Board Geometry/Soldermask Top")
		(3 "B.Mask" user "Board Geometry/Soldermask Bottom")
		(17 "Dwgs.User" user "User.Drawings")
		(19 "Cmts.User" user "User.Comments")
		(21 "Eco1.User" user "User.Eco1")
		(23 "Eco2.User" user "User.Eco2")
		(25 "Edge.Cuts" user "Board Geometry/Outline")
		(27 "Margin" user)
		(31 "F.CrtYd" user "Package Geometry/Place Bound Top")
		(29 "B.CrtYd" user "Package Geometry/Place Bound Bottom")
		(35 "F.Fab" user "Ref Des/Assembly Top")
		(33 "B.Fab" user "Ref Des/Assembly Bottom")
	)
	(footprint ""
		(layer "F.Cu")
		(at 75.938888 -154.194256 -90)
		(property "Reference" "PC4"
			(at -1.663192 0.101346 90)
			(unlocked yes)
			(layer "F.SilkS")
			(effects
				(font
					(size 0.7874 0.5842)
					(thickness 0.1524)
				)
				(justify left)
			)
		)
		(property "Value" ""
			(at 0 0 270)
			(layer "F.Fab")
			(effects
				(font
					(size 1.27 1.27)
				)
			)
		)
		(duplicate_pad_numbers_are_jumpers no)
		(fp_line
			(start -0.7874 0.4064)
			(end -0.7874 -0.4064)
			(stroke
				(width 0.1524)
				(type default)
			)
			(layer "F.SilkS")
		)
		(fp_line
			(start 0.7874 0.4064)
			(end -0.7874 0.4064)
			(stroke
				(width 0.1524)
				(type default)
			)
			(layer "F.SilkS")
		)
		(fp_line
			(start 0 0.381)
			(end 0 -0.381)
			(stroke
				(width 0.1524)
				(type default)
			)
			(layer "F.SilkS")
		)
		(fp_line
			(start -0.7874 -0.4064)
			(end 0.7874 -0.4064)
			(stroke
				(width 0.1524)
				(type default)
			)
			(layer "F.SilkS")
		)
		(fp_line
			(start 0.7874 -0.4064)
			(end 0.7874 0.4064)
			(stroke
				(width 0.1524)
				(type default)
			)
			(layer "F.SilkS")
		)
		(fp_poly
			(pts
				(xy -0.5334 0.254) (xy -0.635 0.254) (xy -0.635 0.2286) (xy -0.635 -0.254) (xy -0.5334 -0.254) (xy -0.5334 -0.2794)
				(xy 0.5334 -0.2794) (xy 0.5334 -0.254) (xy 0.635 -0.254) (xy 0.635 0.254) (xy 0.5334 0.254) (xy 0.5334 0.2794)
				(xy -0.508 0.2794) (xy -0.5334 0.2794)
			)
			(stroke
				(width 0)
				(type default)
			)
			(fill no)
			(layer "F.CrtYd")
		)
		(pad "1" smd rect
			(at 0.40005 0 270)
			(size 0.4572 0.508)
			(layers "F.Cu" "F.Mask" "F.Paste")
			(net "SW_P5V_STB_NODE1_BT")
		)
		(pad "2" smd rect
			(at -0.40005 0 270)
			(size 0.4572 0.508)
			(layers "F.Cu" "F.Mask" "F.Paste")
			(net "SW_P5V_STB_NODE1_PH")
		)
	)
	(footprint ""
		(layer "F.Cu")
		(at 107.925616 -151.017732 -90)
		(property "Reference" "R1130"
			(at 2.599944 1.310386 90)
			(unlocked yes)
			(layer "F.SilkS")
			(effects
				(font
					(size 0.635 0.4064)
					(thickness 0.1524)
				)
				(justify left)
			)
		)
		(property "Value" ""
			(at 0 0 270)
			(layer "F.Fab")
			(effects
				(font
					(size 1.27 1.27)
				)
			)
		)
		(duplicate_pad_numbers_are_jumpers no)
		(fp_line
			(start -1.905 0.8636)
			(end -1.905 -0.8636)
			(stroke
				(width 0.1524)
				(type default)
			)
			(layer "F.SilkS")
		)
		(fp_line
			(start 1.905 0.8636)
			(end -1.905 0.8636)
			(stroke
				(width 0.1524)
				(type default)
			)
			(layer "F.SilkS")
		)
		(fp_line
			(start -1.905 -0.8636)
			(end 1.905 -0.8636)
			(stroke
				(width 0.1524)
				(type default)
			)
			(layer "F.SilkS")
		)
		(fp_line
			(start 1.905 -0.8636)
			(end 1.905 0.8636)
			(stroke
				(width 0.1524)
				(type default)
			)
			(layer "F.SilkS")
		)
		(fp_poly
			(pts
				(xy 1.524 0.6858) (xy 1.524 -0.6858) (xy 1.524 -0.7366) (xy -1.524 -0.7366) (xy -1.524 -0.6858)
				(xy -1.524 0.6858) (xy -1.524 0.7366) (xy 1.524 0.7366)
			)
			(stroke
				(width 0)
				(type default)
			)
			(fill no)
			(layer "F.CrtYd")
		)
		(pad "1" smd rect
			(at 0.94996 0 270)
			(size 1.1176 1.3716)
			(layers "F.Cu" "F.Mask" "F.Paste")
			(net "P12V_AUX")
		)
		(pad "2" smd rect
			(at -0.94996 0 270)
			(size 1.1176 1.3716)
			(layers "F.Cu" "F.Mask" "F.Paste")
			(net "N52411159")
		)
	)
	(footprint ""
		(layer "F.Cu")
		(at 12.213082 -23.12416 180)
		(property "Reference" "U52"
			(at 5.611368 -0.876046 90)
			(unlocked yes)
			(layer "F.SilkS")
			(effects
				(font
					(size 0.7874 0.5842)
					(thickness 0.1524)
				)
				(justify left)
			)
		)
		(property "Value" ""
			(at 0 0 180)
			(layer "F.Fab")
			(effects
				(font
					(size 1.27 1.27)
				)
			)
		)
		(duplicate_pad_numbers_are_jumpers no)
		(fp_line
			(start 4.9022 2.0066)
			(end -4.9022 2.0066)
			(stroke
				(width 0.1524)
				(type default)
			)
			(layer "F.SilkS")
		)
		(fp_line
			(start 4.9022 -2.0066)
			(end 4.9022 2.0066)
			(stroke
				(width 0.1524)
				(type default)
			)
			(layer "F.SilkS")
		)
		(fp_line
			(start -4.318 0)
			(end -4.9022 -0.5842)
			(stroke
				(width 0.1524)
				(type default)
			)
			(layer "F.SilkS")
		)
		(fp_line
			(start -4.9022 2.0066)
			(end -4.9022 0.5842)
			(stroke
				(width 0.1524)
				(type default)
			)
			(layer "F.SilkS")
		)
		(fp_line
			(start -4.9022 0.5842)
			(end -4.318 0)
			(stroke
				(width 0.1524)
				(type default)
			)
			(layer "F.SilkS")
		)
		(fp_line
			(start -4.9022 -0.5842)
			(end -4.9022 -2.0066)
			(stroke
				(width 0.1524)
				(type default)
			)
			(layer "F.SilkS")
		)
		(fp_line
			(start -4.9022 -2.0066)
			(end 4.9022 -2.0066)
			(stroke
				(width 0.1524)
				(type default)
			)
			(layer "F.SilkS")
		)
		(fp_circle
			(center -4.318 1.524)
			(end -4.572 1.524)
			(stroke
				(width 0.1524)
				(type default)
			)
			(fill no)
			(layer "F.SilkS")
		)
		(fp_rect
			(start -4.9022 3.6703)
			(end 4.9022 -3.6703)
			(stroke
				(width 0)
				(type default)
			)
			(fill no)
			(layer "F.CrtYd")
		)
		(pad "1" smd rect
			(at -4.225036 2.921 180)
			(size 0.3556 1.4986)
			(layers "F.Cu" "F.Mask" "F.Paste")
			(net "N54251527")
		)
		(pad "2" smd rect
			(at -3.57505 2.921 180)
			(size 0.3556 1.4986)
			(layers "F.Cu" "F.Mask" "F.Paste")
			(net "N54251529")
		)
		(pad "3" smd rect
			(at -2.925064 2.921 180)
			(size 0.3556 1.4986)
			(layers "F.Cu" "F.Mask" "F.Paste")
			(net "N54251541")
		)
		(pad "4" smd rect
			(at -2.275078 2.921 180)
			(size 0.3556 1.4986)
			(layers "F.Cu" "F.Mask" "F.Paste")
			(net "UART_RX_P2_L")
		)
		(pad "5" smd rect
			(at -1.625092 2.921 180)
			(size 0.3556 1.4986)
			(layers "F.Cu" "F.Mask" "F.Paste")
			(net "UART_DSR_P2_L_N")
		)
		(pad "6" smd rect
			(at -0.975106 2.921 180)
			(size 0.3556 1.4986)
			(layers "F.Cu" "F.Mask" "F.Paste")
			(net "UART_CTS_P2_L_N")
		)
		(pad "7" smd rect
			(at -0.32512 2.921 180)
			(size 0.3556 1.4986)
			(layers "F.Cu" "F.Mask" "F.Paste")
			(net "N54251449")
		)
		(pad "8" smd rect
			(at 0.32512 2.921 180)
			(size 0.3556 1.4986)
			(layers "F.Cu" "F.Mask" "F.Paste")
			(net "N54251449")
		)
		(pad "9" smd rect
			(at 0.975106 2.921 180)
			(size 0.3556 1.4986)
			(layers "F.Cu" "F.Mask" "F.Paste")
			(net "UART_RTS_P2_L_N")
		)
		(pad "10" smd rect
			(at 1.625092 2.921 180)
			(size 0.3556 1.4986)
			(layers "F.Cu" "F.Mask" "F.Paste")
			(net "UART_TX_P2_L")
		)
		(pad "11" smd rect
			(at 2.275078 2.921 180)
			(size 0.3556 1.4986)
			(layers "F.Cu" "F.Mask" "F.Paste")
			(net "UART_DTR_P2_L_N")
		)
		(pad "12" smd rect
			(at 2.925064 2.921 180)
			(size 0.3556 1.4986)
			(layers "F.Cu" "F.Mask" "F.Paste")
			(net "UART_DTR_P2_N")
		)
		(pad "13" smd rect
			(at 3.57505 2.921 180)
			(size 0.3556 1.4986)
			(layers "F.Cu" "F.Mask" "F.Paste")
			(net "UART_TX_P2")
		)
		(pad "14" smd rect
			(at 4.225036 2.921 180)
			(size 0.3556 1.4986)
			(layers "F.Cu" "F.Mask" "F.Paste")
			(net "UART_RTS_P2_N")
		)
		(pad "15" smd rect
			(at 4.225036 -2.921 180)
			(size 0.3556 1.4986)
			(layers "F.Cu" "F.Mask" "F.Paste")
			(net "Net_501")
		)
		(pad "16" smd rect
			(at 3.57505 -2.921 180)
			(size 0.3556 1.4986)
			(layers "F.Cu" "F.Mask" "F.Paste")
			(net "Net_502")
		)
		(pad "17" smd rect
			(at 2.925064 -2.921 180)
			(size 0.3556 1.4986)
			(layers "F.Cu" "F.Mask" "F.Paste")
			(net "UART_CTS_P2_N")
		)
		(pad "18" smd rect
			(at 2.275078 -2.921 180)
			(size 0.3556 1.4986)
			(layers "F.Cu" "F.Mask" "F.Paste")
			(net "UART_DSR_P2_N")
		)
		(pad "19" smd rect
			(at 1.625092 -2.921 180)
			(size 0.3556 1.4986)
			(layers "F.Cu" "F.Mask" "F.Paste")
			(net "UART_RX_P2")
		)
		(pad "20" smd rect
			(at 0.975106 -2.921 180)
			(size 0.3556 1.4986)
			(layers "F.Cu" "F.Mask" "F.Paste")
			(net "Net_2258")
		)
		(pad "21" smd rect
			(at 0.32512 -2.921 180)
			(size 0.3556 1.4986)
			(layers "F.Cu" "F.Mask" "F.Paste")
			(net "Net_2259")
		)
		(pad "22" smd rect
			(at -0.32512 -2.921 180)
			(size 0.3556 1.4986)
			(layers "F.Cu" "F.Mask" "F.Paste")
			(net "N54251489")
		)
		(pad "23" smd rect
			(at -0.975106 -2.921 180)
			(size 0.3556 1.4986)
			(layers "F.Cu" "F.Mask" "F.Paste")
			(net "N54251487")
		)
		(pad "24" smd rect
			(at -1.625092 -2.921 180)
			(size 0.3556 1.4986)
			(layers "F.Cu" "F.Mask" "F.Paste")
			(net "N54251519")
		)
		(pad "25" smd rect
			(at -2.275078 -2.921 180)
			(size 0.3556 1.4986)
			(layers "F.Cu" "F.Mask" "F.Paste")
			(net "GND")
		)
		(pad "26" smd rect
			(at -2.925064 -2.921 180)
			(size 0.3556 1.4986)
			(layers "F.Cu" "F.Mask" "F.Paste")
			(net "P3V3_NODE1")
		)
		(pad "27" smd rect
			(at -3.57505 -2.921 180)
			(size 0.3556 1.4986)
			(layers "F.Cu" "F.Mask" "F.Paste")
			(net "N54251539")
		)
		(pad "28" smd rect
			(at -4.225036 -2.921 180)
			(size 0.3556 1.4986)
			(layers "F.Cu" "F.Mask" "F.Paste")
			(net "N54251517")
		)
	)
	(footprint ""
		(layer "F.Cu")
		(at 117.33276 -188.126624 90)
		(property "Reference" "C751"
			(at 4.839208 0.193802 90)
			(unlocked yes)
			(layer "F.SilkS")
			(effects
				(font
					(size 0.7874 0.5842)
					(thickness 0.1524)
				)
				(justify left)
			)
		)
		(property "Value" ""
			(at 0 0 90)
			(layer "F.Fab")
			(effects
				(font
					(size 1.27 1.27)
				)
			)
		)
		(duplicate_pad_numbers_are_jumpers no)
		(fp_line
			(start 0.7874 -0.4064)
			(end 0.7874 0.4064)
			(stroke
				(width 0.1524)
				(type default)
			)
			(layer "F.SilkS")
		)
		(fp_line
			(start -0.7874 -0.4064)
			(end 0.7874 -0.4064)
			(stroke
				(width 0.1524)
				(type default)
			)
			(layer "F.SilkS")
		)
		(fp_line
			(start 0 0.381)
			(end 0 -0.381)
			(stroke
				(width 0.1524)
				(type default)
			)
			(layer "F.SilkS")
		)
		(fp_line
			(start 0.7874 0.4064)
			(end -0.7874 0.4064)
			(stroke
				(width 0.1524)
				(type default)
			)
			(layer "F.SilkS")
		)
		(fp_line
			(start -0.7874 0.4064)
			(end -0.7874 -0.4064)
			(stroke
				(width 0.1524)
				(type default)
			)
			(layer "F.SilkS")
		)
		(fp_poly
			(pts
				(xy -0.5334 0.254) (xy -0.635 0.254) (xy -0.635 0.2286) (xy -0.635 -0.254) (xy -0.5334 -0.254) (xy -0.5334 -0.2794)
				(xy 0.5334 -0.2794) (xy 0.5334 -0.254) (xy 0.635 -0.254) (xy 0.635 0.254) (xy 0.5334 0.254) (xy 0.5334 0.2794)
				(xy -0.508 0.2794) (xy -0.5334 0.2794)
			)
			(stroke
				(width 0)
				(type default)
			)
			(fill no)
			(layer "F.CrtYd")
		)
		(pad "1" smd rect
			(at 0.40005 0 90)
			(size 0.4572 0.508)
			(layers "F.Cu" "F.Mask" "F.Paste")
			(net "UART_T8_NODE2_TXD_R")
		)
		(pad "2" smd rect
			(at -0.40005 0 90)
			(size 0.4572 0.508)
			(layers "F.Cu" "F.Mask" "F.Paste")
			(net "GND")
		)
	)
	(footprint ""
		(layer "F.Cu")
		(at 45.130974 -123.21667 90)
		(property "Reference" "U16"
			(at -0.094742 3.428746 0)
			(unlocked yes)
			(layer "F.SilkS")
			(effects
				(font
					(size 0.7874 0.5842)
					(thickness 0.1524)
				)
			)
		)
		(property "Value" ""
			(at 0 0 90)
			(layer "F.Fab")
			(effects
				(font
					(size 1.27 1.27)
				)
			)
		)
		(duplicate_pad_numbers_are_jumpers no)
		(fp_line
			(start 1.1176 -1.7018)
			(end 1.1176 1.7018)
			(stroke
				(width 0.1524)
				(type default)
			)
			(layer "F.SilkS")
		)
		(fp_line
			(start -1.1176 -1.7018)
			(end 1.1176 -1.7018)
			(stroke
				(width 0.1524)
				(type default)
			)
			(layer "F.SilkS")
		)
		(fp_line
			(start -1.1176 -1.7018)
			(end -1.1176 -0.254)
			(stroke
				(width 0.1524)
				(type default)
			)
			(layer "F.SilkS")
		)
		(fp_line
			(start -1.1176 -0.254)
			(end -0.7112 0)
			(stroke
				(width 0.1524)
				(type default)
			)
			(layer "F.SilkS")
		)
		(fp_line
			(start -0.7112 0)
			(end -1.1176 0.254)
			(stroke
				(width 0.1524)
				(type default)
			)
			(layer "F.SilkS")
		)
		(fp_line
			(start -1.1176 0.254)
			(end -1.1176 1.7018)
			(stroke
				(width 0.1524)
				(type default)
			)
			(layer "F.SilkS")
		)
		(fp_line
			(start 1.1176 1.7018)
			(end -1.1176 1.7018)
			(stroke
				(width 0.1524)
				(type default)
			)
			(layer "F.SilkS")
		)
		(fp_poly
			(pts
				(xy -0.675386 1.8161) (xy -0.446786 2.4003) (xy -0.878586 2.4003)
			)
			(stroke
				(width 0)
				(type default)
			)
			(fill yes)
			(layer "F.SilkS")
		)
		(fp_rect
			(start -1.1176 1.5494)
			(end 1.1176 -1.5494)
			(stroke
				(width 0)
				(type default)
			)
			(fill no)
			(layer "F.CrtYd")
		)
		(fp_line
			(start 1.1176 -1.5494)
			(end 1.1176 1.5494)
			(stroke
				(width 0.1)
				(type default)
			)
			(layer "F.Fab")
		)
		(fp_line
			(start -1.1176 -1.5494)
			(end 1.1176 -1.5494)
			(stroke
				(width 0.1)
				(type default)
			)
			(layer "F.Fab")
		)
		(fp_line
			(start -1.1176 -1.5494)
			(end -1.1176 -0.254)
			(stroke
				(width 0.1)
				(type default)
			)
			(layer "F.Fab")
		)
		(fp_line
			(start -1.1176 -0.254)
			(end -1.1176 0.254)
			(stroke
				(width 0.1)
				(type default)
			)
			(layer "F.Fab")
		)
		(fp_line
			(start -1.1176 0.254)
			(end -1.1176 1.5494)
			(stroke
				(width 0.1)
				(type default)
			)
			(layer "F.Fab")
		)
		(fp_line
			(start 1.1176 1.5494)
			(end -1.1176 1.5494)
			(stroke
				(width 0.1)
				(type default)
			)
			(layer "F.Fab")
		)
		(fp_poly
			(pts
				(xy -0.675386 1.8161) (xy -0.446786 2.4003) (xy -0.878586 2.4003)
			)
			(stroke
				(width 0)
				(type default)
			)
			(fill yes)
			(layer "F.Fab")
		)
		(pad "1" smd rect
			(at -0.649986 0.962406 90)
			(size 0.3302 1.1684)
			(layers "F.Cu" "F.Mask" "F.Paste")
			(net "Net_1785")
		)
		(pad "2" smd rect
			(at 0 0.962406 90)
			(size 0.3302 1.1684)
			(layers "F.Cu" "F.Mask" "F.Paste")
			(net "FM_BMC_NODE1_RESET_L")
		)
		(pad "3" smd rect
			(at 0.649986 0.962406 90)
			(size 0.3302 1.1684)
			(layers "F.Cu" "F.Mask" "F.Paste")
			(net "GND")
		)
		(pad "4" smd rect
			(at 0.649986 -0.962406 90)
			(size 0.3302 1.1684)
			(layers "F.Cu" "F.Mask" "F.Paste")
			(net "BMC_NODE1_DDR_RST_L")
		)
		(pad "5" smd rect
			(at -0.649986 -0.962406 90)
			(size 0.3302 1.1684)
			(layers "F.Cu" "F.Mask" "F.Paste")
			(net "P3V3_NODE1")
		)
	)
	(footprint ""
		(layer "F.Cu")
		(at 184.7342 -173.4058 180)
		(property "Reference" "R1073"
			(at -9.9568 -17.42567 0)
			(unlocked yes)
			(layer "F.SilkS")
			(effects
				(font
					(size 0.7874 0.5842)
					(thickness 0.1524)
				)
				(justify left)
			)
		)
		(property "Value" ""
			(at 0 0 180)
			(layer "F.Fab")
			(effects
				(font
					(size 1.27 1.27)
				)
			)
		)
		(duplicate_pad_numbers_are_jumpers no)
		(fp_line
			(start 0.7874 0.4064)
			(end -0.7874 0.4064)
			(stroke
				(width 0.1524)
				(type default)
			)
			(layer "F.SilkS")
		)
		(fp_line
			(start 0.7874 -0.4064)
			(end 0.7874 0.4064)
			(stroke
				(width 0.1524)
				(type default)
			)
			(layer "F.SilkS")
		)
		(fp_line
			(start -0.7874 0.4064)
			(end -0.7874 -0.4064)
			(stroke
				(width 0.1524)
				(type default)
			)
			(layer "F.SilkS")
		)
		(fp_line
			(start -0.7874 -0.4064)
			(end 0.7874 -0.4064)
			(stroke
				(width 0.1524)
				(type default)
			)
			(layer "F.SilkS")
		)
		(fp_poly
			(pts
				(xy -0.508 0.2794) (xy -0.508 0.2286) (xy -0.635 0.2286) (xy -0.635 -0.254) (xy -0.5334 -0.254)
				(xy -0.5334 -0.2794) (xy 0.5334 -0.2794) (xy 0.5334 -0.254) (xy 0.635 -0.254) (xy 0.635 0.254) (xy 0.5334 0.254)
				(xy 0.5334 0.2794)
			)
			(stroke
				(width 0)
				(type default)
			)
			(fill no)
			(layer "F.CrtYd")
		)
		(pad "1" smd rect
			(at 0.40005 0 180)
			(size 0.4572 0.508)
			(layers "F.Cu" "F.Mask" "F.Paste")
			(net "POWER_SW2_PWR_CTR_12V")
		)
		(pad "2" smd rect
			(at -0.40005 0 180)
			(size 0.4572 0.508)
			(layers "F.Cu" "F.Mask" "F.Paste")
			(net "POWER_SW2_PWR_CTR_12V_R")
		)
	)
	(footprint ""
		(layer "F.Cu")
		(at 25.973278 -44.100496 -90)
		(property "Reference" "R632"
			(at 4.987036 -0.546608 90)
			(unlocked yes)
			(layer "F.SilkS")
			(effects
				(font
					(size 0.7874 0.5842)
					(thickness 0.1524)
				)
				(justify left)
			)
		)
		(property "Value" ""
			(at 0 0 270)
			(layer "F.Fab")
			(effects
				(font
					(size 1.27 1.27)
				)
			)
		)
		(duplicate_pad_numbers_are_jumpers no)
		(fp_line
			(start -0.7874 0.4064)
			(end -0.7874 -0.4064)
			(stroke
				(width 0.1524)
				(type default)
			)
			(layer "F.SilkS")
		)
		(fp_line
			(start 0.7874 0.4064)
			(end -0.7874 0.4064)
			(stroke
				(width 0.1524)
				(type default)
			)
			(layer "F.SilkS")
		)
		(fp_line
			(start -0.7874 -0.4064)
			(end 0.7874 -0.4064)
			(stroke
				(width 0.1524)
				(type default)
			)
			(layer "F.SilkS")
		)
		(fp_line
			(start 0.7874 -0.4064)
			(end 0.7874 0.4064)
			(stroke
				(width 0.1524)
				(type default)
			)
			(layer "F.SilkS")
		)
		(fp_poly
			(pts
				(xy -0.508 0.2794) (xy -0.508 0.2286) (xy -0.635 0.2286) (xy -0.635 -0.254) (xy -0.5334 -0.254)
				(xy -0.5334 -0.2794) (xy 0.5334 -0.2794) (xy 0.5334 -0.254) (xy 0.635 -0.254) (xy 0.635 0.254) (xy 0.5334 0.254)
				(xy 0.5334 0.2794)
			)
			(stroke
				(width 0)
				(type default)
			)
			(fill no)
			(layer "F.CrtYd")
		)
		(pad "1" smd rect
			(at 0.40005 0 270)
			(size 0.4572 0.508)
			(layers "F.Cu" "F.Mask" "F.Paste")
			(net "P3V3_NODE1")
		)
		(pad "2" smd rect
			(at -0.40005 0 270)
			(size 0.4572 0.508)
			(layers "F.Cu" "F.Mask" "F.Paste")
			(net "SMB_BMC_NODE1_DDC_DAT")
		)
	)
)
